(kicad_pcb
	(version 20260206)
	(generator "pcbnew")
	(generator_version "10.0")
	(general
		(thickness 1.6)
		(legacy_teardrops no)
	)
	(paper "A4")
	(title_block
		(title "timecard-production-celestica-r4006 — R4006-B0001-02_R01.brd")
		(comment 1 "Time Appliance Project (Time Card) / footprints 713-716 of 1113")
	)
	(layers
		(0 "F.Cu" signal "TOP")
		(4 "In1.Cu" signal "L02_GND1")
		(6 "In2.Cu" signal "L03_SIG1")
		(8 "In3.Cu" signal "L04_GND2")
		(10 "In4.Cu" signal "L05_VCC1")
		(12 "In5.Cu" signal "L06_VCC2")
		(14 "In6.Cu" signal "L07_GND3")
		(16 "In7.Cu" signal "L08_SIG2")
		(18 "In8.Cu" signal "L09_GND4")
		(2 "B.Cu" signal "BOTTOM")
		(9 "F.Adhes" user "F.Adhesive")
		(11 "B.Adhes" user "B.Adhesive")
		(13 "F.Paste" user "Package Geometry/Pastemask Top")
		(15 "B.Paste" user "Package Geometry/Pastemask Bottom")
		(5 "F.SilkS" user "Ref Des/Silkscreen Top")
		(7 "B.SilkS" user "Ref Des/Silkscreen Bottom")
		(1 "F.Mask" user "Board Geometry/Soldermask Top")
		(3 "B.Mask" user "Board Geometry/Soldermask Bottom")
		(17 "Dwgs.User" user "User.Drawings")
		(19 "Cmts.User" user "User.Comments")
		(21 "Eco1.User" user "User.Eco1")
		(23 "Eco2.User" user "User.Eco2")
		(25 "Edge.Cuts" user "Board Geometry/Outline")
		(27 "Margin" user)
		(31 "F.CrtYd" user "Package Geometry/Place Bound Top")
		(29 "B.CrtYd" user "Package Geometry/Place Bound Bottom")
		(35 "F.Fab" user "Ref Des/Assembly Top")
		(33 "B.Fab" user "Ref Des/Assembly Bottom")
	)
	(footprint ""
		(layer "B.Cu")
		(at 144.9832 -75.3364 -90)
		(property "Reference" "CR6"
			(at 1.1684 -3.44043 270)
			(unlocked yes)
			(layer "B.SilkS")
			(effects
				(font
					(size 0.7874 0.5842)
					(thickness 0.1524)
				)
				(justify mirror)
			)
		)
		(property "Value" ""
			(at 0 0 90)
			(layer "B.Fab")
			(effects
				(font
					(size 1.27 1.27)
				)
				(justify mirror)
			)
		)
		(property "User Part Number" "PARTNUM*"
			(at -0.254 3.718306 270)
			(unlocked yes)
			(layer "Cmts.User")
			(hide yes)
			(effects
				(font
					(size 0.7874 0.5842)
					(thickness 0.1524)
				)
				(justify mirror)
			)
		)
		(property "Device Type" "DIODE_4_V1-G122-10123-01"
			(at -0.254 2.702306 270)
			(unlocked yes)
			(layer "B.Fab")
			(hide yes)
			(effects
				(font
					(size 0.7874 0.5842)
					(thickness 0.1524)
				)
				(justify mirror)
			)
		)
		(duplicate_pad_numbers_are_jumpers no)
		(fp_line
			(start -2.0828 1.7018)
			(end 2.0828 1.7018)
			(stroke
				(width 0.1)
				(type default)
			)
			(layer "B.SilkS")
		)
		(fp_line
			(start 2.0828 1.7018)
			(end 2.0828 -1.7018)
			(stroke
				(width 0.1)
				(type default)
			)
			(layer "B.SilkS")
		)
		(fp_line
			(start -2.0828 -1.7018)
			(end -2.0828 1.7018)
			(stroke
				(width 0.1)
				(type default)
			)
			(layer "B.SilkS")
		)
		(fp_line
			(start 2.0828 -1.7018)
			(end -2.0828 -1.7018)
			(stroke
				(width 0.1)
				(type default)
			)
			(layer "B.SilkS")
		)
		(fp_poly
			(pts
				(arc
					(start 2.6162 -1.27)
					(mid 2.6162 -0.508)
					(end 2.6162 -1.27)
				)
			)
			(stroke
				(width 0)
				(type default)
			)
			(fill yes)
			(layer "B.SilkS")
		)
		(fp_rect
			(start -2.3368 1.9304)
			(end 2.3368 -1.9304)
			(stroke
				(width 0)
				(type default)
			)
			(fill no)
			(layer "B.CrtYd")
		)
		(fp_line
			(start -0.6477 1.42875)
			(end 0.6477 1.42875)
			(stroke
				(width 0.1)
				(type default)
			)
			(layer "B.Fab")
		)
		(fp_line
			(start 0.6477 1.42875)
			(end 0.6477 -1.42875)
			(stroke
				(width 0.1)
				(type default)
			)
			(layer "B.Fab")
		)
		(fp_line
			(start -1.143 1.1811)
			(end -0.6477 1.1811)
			(stroke
				(width 0.1)
				(type default)
			)
			(layer "B.Fab")
		)
		(fp_line
			(start -0.6477 1.1811)
			(end -0.6477 0.7239)
			(stroke
				(width 0.1)
				(type default)
			)
			(layer "B.Fab")
		)
		(fp_line
			(start 0.6477 1.1811)
			(end 1.143 1.1811)
			(stroke
				(width 0.1)
				(type default)
			)
			(layer "B.Fab")
		)
		(fp_line
			(start 1.143 1.1811)
			(end 1.143 0.7239)
			(stroke
				(width 0.1)
				(type default)
			)
			(layer "B.Fab")
		)
		(fp_line
			(start -1.143 0.7239)
			(end -1.143 1.1811)
			(stroke
				(width 0.1)
				(type default)
			)
			(layer "B.Fab")
		)
		(fp_line
			(start -0.6477 0.7239)
			(end -1.143 0.7239)
			(stroke
				(width 0.1)
				(type default)
			)
			(layer "B.Fab")
		)
		(fp_line
			(start 0.6477 0.7239)
			(end 0.6477 1.1811)
			(stroke
				(width 0.1)
				(type default)
			)
			(layer "B.Fab")
		)
		(fp_line
			(start 1.143 0.7239)
			(end 0.6477 0.7239)
			(stroke
				(width 0.1)
				(type default)
			)
			(layer "B.Fab")
		)
		(fp_line
			(start 0.6477 -0.3175)
			(end 1.143 -0.3175)
			(stroke
				(width 0.1)
				(type default)
			)
			(layer "B.Fab")
		)
		(fp_line
			(start 1.143 -0.3175)
			(end 1.143 -1.1811)
			(stroke
				(width 0.1)
				(type default)
			)
			(layer "B.Fab")
		)
		(fp_line
			(start -1.143 -0.7239)
			(end -0.6477 -0.7239)
			(stroke
				(width 0.1)
				(type default)
			)
			(layer "B.Fab")
		)
		(fp_line
			(start -0.6477 -0.7239)
			(end -0.6477 -1.1811)
			(stroke
				(width 0.1)
				(type default)
			)
			(layer "B.Fab")
		)
		(fp_line
			(start -1.143 -1.1811)
			(end -1.143 -0.7239)
			(stroke
				(width 0.1)
				(type default)
			)
			(layer "B.Fab")
		)
		(fp_line
			(start -0.6477 -1.1811)
			(end -1.143 -1.1811)
			(stroke
				(width 0.1)
				(type default)
			)
			(layer "B.Fab")
		)
		(fp_line
			(start 0.6477 -1.1811)
			(end 0.6477 -0.3175)
			(stroke
				(width 0.1)
				(type default)
			)
			(layer "B.Fab")
		)
		(fp_line
			(start 1.143 -1.1811)
			(end 0.6477 -1.1811)
			(stroke
				(width 0.1)
				(type default)
			)
			(layer "B.Fab")
		)
		(fp_line
			(start -0.6477 -1.42875)
			(end -0.6477 1.42875)
			(stroke
				(width 0.1)
				(type default)
			)
			(layer "B.Fab")
		)
		(fp_line
			(start 0.6477 -1.42875)
			(end -0.6477 -1.42875)
			(stroke
				(width 0.1)
				(type default)
			)
			(layer "B.Fab")
		)
		(fp_poly
			(pts
				(arc
					(start 0.381 -0.9398)
					(mid 0.381 -0.5588)
					(end 0.381 -0.9398)
				)
			)
			(stroke
				(width 0)
				(type default)
			)
			(fill yes)
			(layer "B.Fab")
		)
		(fp_text user "3"
			(at -2.72923 1.0541 0)
			(unlocked yes)
			(layer "B.SilkS")
			(effects
				(font
					(size 0.7874 0.5842)
					(thickness 0.1524)
				)
				(justify left mirror)
			)
		)
		(fp_text user "2"
			(at 2.85877 0.9271 0)
			(unlocked yes)
			(layer "B.SilkS")
			(effects
				(font
					(size 0.7874 0.5842)
					(thickness 0.1524)
				)
				(justify left mirror)
			)
		)
		(fp_text user "4"
			(at -2.72923 -1.7399 0)
			(unlocked yes)
			(layer "B.SilkS")
			(effects
				(font
					(size 0.7874 0.5842)
					(thickness 0.1524)
				)
				(justify left mirror)
			)
		)
		(fp_text user "2"
			(at 2.08407 0.7112 0)
			(unlocked yes)
			(layer "B.Fab")
			(effects
				(font
					(size 0.7874 0.5842)
					(thickness 0.1524)
				)
				(justify left mirror)
			)
		)
		(fp_text user "3"
			(at -1.89103 0.669036 0)
			(unlocked yes)
			(layer "B.Fab")
			(effects
				(font
					(size 0.7874 0.5842)
					(thickness 0.1524)
				)
				(justify left mirror)
			)
		)
		(fp_text user "4"
			(at -1.91643 -1.261618 0)
			(unlocked yes)
			(layer "B.Fab")
			(effects
				(font
					(size 0.7874 0.5842)
					(thickness 0.1524)
				)
				(justify left mirror)
			)
		)
		(pad "1" smd rect
			(at 1.1049 -0.7493 90)
			(size 1.4478 1.0922)
			(layers "B.Cu" "B.Mask" "B.Paste")
			(net "SG")
		)
		(pad "2" smd rect
			(at 1.1049 0.9525 90)
			(size 1.4478 0.9906)
			(layers "B.Cu" "B.Mask" "B.Paste")
			(net "FT4232_FPGA_TMS")
		)
		(pad "3" smd rect
			(at -1.1049 0.9525 90)
			(size 1.4478 0.9906)
			(layers "B.Cu" "B.Mask" "B.Paste")
			(net "FT4232_FPGA_TDI")
		)
		(pad "4" smd rect
			(at -1.1049 -0.9525 90)
			(size 1.4478 0.9906)
			(layers "B.Cu" "B.Mask" "B.Paste")
			(net "Net_623")
		)
		(zone
			(layer "B.Cu")
			(hatch none 0.5)
			(connect_pads
				(clearance 0)
			)
			(min_thickness 0.25)
			(keepout
				(tracks allowed)
				(vias not_allowed)
				(pads allowed)
				(copperpour not_allowed)
				(footprints allowed)
			)
			(placement
				(enabled no)
				(sheetname "")
			)
			(fill
				(thermal_gap 0.5)
				(thermal_bridge_width 0.5)
				(island_removal_mode 0)
			)
			(polygon
				(pts
					(xy 146.2786 -74.6887) (xy 146.4183 -74.6887) (xy 146.4183 -75.7174) (xy 145.4404 -75.7174) (xy 145.4404 -75.9841)
					(xy 144.526 -75.9841) (xy 144.526 -75.7174) (xy 143.5481 -75.7174) (xy 143.5481 -74.9554) (xy 144.526 -74.9554)
					(xy 144.526 -74.6887) (xy 145.1864 -74.6887) (xy 145.1864 -74.9554) (xy 146.2786 -74.9554)
				)
			)
		)
	)
	(footprint ""
		(layer "B.Cu")
		(at 89.9922 -103.5558)
		(property "Reference" "R53"
			(at 3.7338 0.09017 0)
			(unlocked yes)
			(layer "B.SilkS")
			(effects
				(font
					(size 0.7874 0.5842)
					(thickness 0.1524)
				)
				(justify mirror)
			)
		)
		(property "Value" "VAL*"
			(at -0.02032 2.13233 0)
			(unlocked yes)
			(layer "B.Fab")
			(hide yes)
			(effects
				(font
					(size 0.7874 0.5842)
					(thickness 0.1524)
				)
				(justify mirror)
			)
		)
		(property "Tolerance" "TOL*"
			(at -0.044704 3.05435 0)
			(unlocked yes)
			(layer "Cmts.User")
			(hide yes)
			(effects
				(font
					(size 0.7874 0.5842)
					(thickness 0.1524)
				)
				(justify mirror)
			)
		)
		(property "User Part Number" "PARTNUM*"
			(at -0.02032 4.024884 0)
			(unlocked yes)
			(layer "Cmts.User")
			(hide yes)
			(effects
				(font
					(size 0.7874 0.5842)
					(thickness 0.1524)
				)
				(justify mirror)
			)
		)
		(property "Device Type" "RESISTOR-G152-10344-01,30KOHM,A"
			(at -0.008382 1.210564 0)
			(unlocked yes)
			(layer "B.Fab")
			(hide yes)
			(effects
				(font
					(size 0.7874 0.5842)
					(thickness 0.1524)
				)
				(justify mirror)
			)
		)
		(duplicate_pad_numbers_are_jumpers no)
		(fp_line
			(start -1.143 -0.5588)
			(end 1.143 -0.5588)
			(stroke
				(width 0.1)
				(type default)
			)
			(layer "B.SilkS")
		)
		(fp_line
			(start -1.143 0.5588)
			(end -1.143 -0.5588)
			(stroke
				(width 0.1)
				(type default)
			)
			(layer "B.SilkS")
		)
		(fp_line
			(start 1.143 -0.5588)
			(end 1.143 0.5588)
			(stroke
				(width 0.1)
				(type default)
			)
			(layer "B.SilkS")
		)
		(fp_line
			(start 1.143 0.5588)
			(end -1.143 0.5588)
			(stroke
				(width 0.1)
				(type default)
			)
			(layer "B.SilkS")
		)
		(fp_rect
			(start -1.143 0.5588)
			(end 1.143 -0.5588)
			(stroke
				(width 0)
				(type default)
			)
			(fill no)
			(layer "B.CrtYd")
		)
		(fp_line
			(start -0.508 -0.3048)
			(end 0.508 -0.3048)
			(stroke
				(width 0.1)
				(type default)
			)
			(layer "B.Fab")
		)
		(fp_line
			(start -0.508 0.3048)
			(end -0.508 -0.3048)
			(stroke
				(width 0.1)
				(type default)
			)
			(layer "B.Fab")
		)
		(fp_line
			(start 0.508 -0.3048)
			(end 0.508 0.3048)
			(stroke
				(width 0.1)
				(type default)
			)
			(layer "B.Fab")
		)
		(fp_line
			(start 0.508 0.3048)
			(end -0.508 0.3048)
			(stroke
				(width 0.1)
				(type default)
			)
			(layer "B.Fab")
		)
		(pad "1" smd rect
			(at 0.5334 0 180)
			(size 0.7112 0.6096)
			(layers "B.Cu" "B.Mask" "B.Paste")
			(net "VIN_XP3R3")
		)
		(pad "2" smd rect
			(at -0.5334 0 180)
			(size 0.7112 0.6096)
			(layers "B.Cu" "B.Mask" "B.Paste")
			(net "XP3R3V_EN")
		)
		(zone
			(layer "B.Cu")
			(hatch none 0.5)
			(connect_pads
				(clearance 0)
			)
			(min_thickness 0.25)
			(keepout
				(tracks not_allowed)
				(vias allowed)
				(pads allowed)
				(copperpour not_allowed)
				(footprints allowed)
			)
			(placement
				(enabled no)
				(sheetname "")
			)
			(fill
				(thermal_gap 0.5)
				(thermal_bridge_width 0.5)
				(island_removal_mode 0)
			)
			(polygon
				(pts
					(xy 89.916 -103.251) (xy 90.0684 -103.251) (xy 90.0684 -103.8606) (xy 89.916 -103.8606)
				)
			)
		)
		(zone
			(layer "B.Cu")
			(hatch none 0.5)
			(connect_pads
				(clearance 0)
			)
			(min_thickness 0.25)
			(keepout
				(tracks allowed)
				(vias not_allowed)
				(pads allowed)
				(copperpour not_allowed)
				(footprints allowed)
			)
			(placement
				(enabled no)
				(sheetname "")
			)
			(fill
				(thermal_gap 0.5)
				(thermal_bridge_width 0.5)
				(island_removal_mode 0)
			)
			(polygon
				(pts
					(xy 89.916 -103.251) (xy 90.0684 -103.251) (xy 90.0684 -103.8606) (xy 89.916 -103.8606)
				)
			)
		)
	)
	(footprint ""
		(layer "B.Cu")
		(at 119.34698 -42.82313)
		(property "Reference" "R500"
			(at 2.79527 0.78613 270)
			(unlocked yes)
			(layer "B.SilkS")
			(effects
				(font
					(size 0.635 0.4064)
					(thickness 0.1524)
				)
				(justify mirror)
			)
		)
		(property "Value" "VAL*"
			(at 0 3.718306 0)
			(unlocked yes)
			(layer "B.Fab")
			(hide yes)
			(effects
				(font
					(size 0.7874 0.5842)
					(thickness 0.127)
				)
				(justify mirror)
			)
		)
		(property "Tolerance" "TOL*"
			(at 0 4.861306 0)
			(unlocked yes)
			(layer "Cmts.User")
			(hide yes)
			(effects
				(font
					(size 0.7874 0.5842)
					(thickness 0.127)
				)
				(justify mirror)
			)
		)
		(property "User Part Number" "PARTNUM*"
			(at 0 2.575306 0)
			(unlocked yes)
			(layer "Cmts.User")
			(hide yes)
			(effects
				(font
					(size 0.7874 0.5842)
					(thickness 0.127)
				)
				(justify mirror)
			)
		)
		(property "Device Type" "RESISTOR-G155-14701-01,4.7KOHMA"
			(at 0 1.432306 0)
			(unlocked yes)
			(layer "B.Fab")
			(hide yes)
			(effects
				(font
					(size 0.7874 0.5842)
					(thickness 0.127)
				)
				(justify mirror)
			)
		)
		(duplicate_pad_numbers_are_jumpers no)
		(fp_line
			(start -0.970026 -0.4699)
			(end -0.970026 0.4699)
			(stroke
				(width 0.1)
				(type default)
			)
			(layer "B.SilkS")
		)
		(fp_line
			(start -0.970026 0.4699)
			(end 0.970026 0.4699)
			(stroke
				(width 0.1)
				(type default)
			)
			(layer "B.SilkS")
		)
		(fp_line
			(start 0.970026 -0.4699)
			(end -0.970026 -0.4699)
			(stroke
				(width 0.1)
				(type default)
			)
			(layer "B.SilkS")
		)
		(fp_line
			(start 0.970026 0.4699)
			(end 0.970026 -0.4699)
			(stroke
				(width 0.1)
				(type default)
			)
			(layer "B.SilkS")
		)
		(fp_poly
			(pts
				(xy 0.970026 0.4699) (xy -0.970026 0.4699) (xy -0.970026 -0.4699) (xy 0.970026 -0.4699)
			)
			(stroke
				(width 0)
				(type default)
			)
			(fill no)
			(layer "B.CrtYd")
		)
		(fp_line
			(start -0.508 -0.3048)
			(end -0.508 0.3048)
			(stroke
				(width 0.1)
				(type default)
			)
			(layer "B.Fab")
		)
		(fp_line
			(start -0.508 0.3048)
			(end 0.508 0.3048)
			(stroke
				(width 0.1)
				(type default)
			)
			(layer "B.Fab")
		)
		(fp_line
			(start 0.508 -0.3048)
			(end -0.508 -0.3048)
			(stroke
				(width 0.1)
				(type default)
			)
			(layer "B.Fab")
		)
		(fp_line
			(start 0.508 0.3048)
			(end 0.508 -0.3048)
			(stroke
				(width 0.1)
				(type default)
			)
			(layer "B.Fab")
		)
		(pad "1" smd circle
			(at 0.500126 0 180)
			(size 0.635 0.635)
			(layers "B.Cu" "B.Mask" "B.Paste")
			(net "SG")
		)
		(pad "2" smd circle
			(at -0.500126 0 180)
			(size 0.635 0.635)
			(layers "B.Cu" "B.Mask" "B.Paste")
			(net "ANT3_IN")
		)
	)
	(footprint ""
		(layer "B.Cu")
		(at 114.847116 -42.323004 90)
		(property "Reference" "C207"
			(at -1.302004 -41.726866 270)
			(unlocked yes)
			(layer "B.SilkS")
			(effects
				(font
					(size 0.635 0.4064)
					(thickness 0.1524)
				)
				(justify mirror)
			)
		)
		(property "Value" "VAL*"
			(at 0 3.718306 90)
			(unlocked yes)
			(layer "B.Fab")
			(hide yes)
			(effects
				(font
					(size 0.7874 0.5842)
					(thickness 0.127)
				)
				(justify mirror)
			)
		)
		(property "Device Type" "CAPACITOR-G105-0B104-CK,0.1UF,A"
			(at 0 1.432306 90)
			(unlocked yes)
			(layer "B.Fab")
			(hide yes)
			(effects
				(font
					(size 0.7874 0.5842)
					(thickness 0.127)
				)
				(justify mirror)
			)
		)
		(property "User Part Number" "PARTNUM*"
			(at 0 2.575306 90)
			(unlocked yes)
			(layer "Cmts.User")
			(hide yes)
			(effects
				(font
					(size 0.7874 0.5842)
					(thickness 0.127)
				)
				(justify mirror)
			)
		)
		(property "Tolerance" "TOL*"
			(at 0 4.861306 90)
			(unlocked yes)
			(layer "Cmts.User")
			(hide yes)
			(effects
				(font
					(size 0.7874 0.5842)
					(thickness 0.127)
				)
				(justify mirror)
			)
		)
		(duplicate_pad_numbers_are_jumpers no)
		(fp_line
			(start 0.970026 -0.4699)
			(end -0.970026 -0.4699)
			(stroke
				(width 0.1)
				(type default)
			)
			(layer "B.SilkS")
		)
		(fp_line
			(start -0.970026 -0.4699)
			(end -0.970026 0.4699)
			(stroke
				(width 0.1)
				(type default)
			)
			(layer "B.SilkS")
		)
		(fp_line
			(start 0.970026 0.4699)
			(end 0.970026 -0.4699)
			(stroke
				(width 0.1)
				(type default)
			)
			(layer "B.SilkS")
		)
		(fp_line
			(start -0.970026 0.4699)
			(end 0.970026 0.4699)
			(stroke
				(width 0.1)
				(type default)
			)
			(layer "B.SilkS")
		)
		(fp_poly
			(pts
				(xy 0.970026 0.4699) (xy -0.970026 0.4699) (xy -0.970026 -0.4699) (xy 0.970026 -0.4699)
			)
			(stroke
				(width 0)
				(type default)
			)
			(fill no)
			(layer "B.CrtYd")
		)
		(fp_line
			(start 0.508 -0.3048)
			(end -0.508 -0.3048)
			(stroke
				(width 0.1)
				(type default)
			)
			(layer "B.Fab")
		)
		(fp_line
			(start -0.508 -0.3048)
			(end -0.508 0.3048)
			(stroke
				(width 0.1)
				(type default)
			)
			(layer "B.Fab")
		)
		(fp_line
			(start 0.508 0.3048)
			(end 0.508 -0.3048)
			(stroke
				(width 0.1)
				(type default)
			)
			(layer "B.Fab")
		)
		(fp_line
			(start -0.508 0.3048)
			(end 0.508 0.3048)
			(stroke
				(width 0.1)
				(type default)
			)
			(layer "B.Fab")
		)
		(pad "1" smd circle
			(at 0.500126 0 270)
			(size 0.635 0.635)
			(layers "B.Cu" "B.Mask" "B.Paste")
			(net "XP1R0V_FPGA_VCCINT")
		)
		(pad "2" smd circle
			(at -0.500126 0 270)
			(size 0.635 0.635)
			(layers "B.Cu" "B.Mask" "B.Paste")
			(net "SG")
		)
	)
)
